(kicad_pcb
	(version 20260206)
	(generator "pcbnew")
	(generator_version "10.0")
	(general
		(thickness 1.6)
		(legacy_teardrops no)
	)
	(paper "A4")
	(title_block
		(title "Wiwynn_Tioga_Pass_MB.brd")
		(comment 1 "Tioga Pass / footprint 190 of 4770 (U2D1), pads 3483-3595 of 3647")
	)
	(layers
		(0 "F.Cu" signal "TOP")
		(4 "In1.Cu" signal "L2GND")
		(6 "In2.Cu" signal "L3")
		(8 "In3.Cu" signal "L4GND")
		(10 "In4.Cu" signal "L5")
		(12 "In5.Cu" signal "L6GND")
		(14 "In6.Cu" signal "L7VCC")
		(16 "In7.Cu" signal "L8VCC")
		(18 "In8.Cu" signal "L9GND")
		(20 "In9.Cu" signal "L10")
		(22 "In10.Cu" signal "L11GND")
		(24 "In11.Cu" signal "L12")
		(26 "In12.Cu" signal "L13GND")
		(2 "B.Cu" signal "BOTTOM")
		(9 "F.Adhes" user "F.Adhesive")
		(11 "B.Adhes" user "B.Adhesive")
		(13 "F.Paste" user "Package Geometry/Pastemask Top")
		(15 "B.Paste" user "Package Geometry/Pastemask Bottom")
		(5 "F.SilkS" user "Ref Des/Silkscreen Top")
		(7 "B.SilkS" user "Ref Des/Silkscreen Bottom")
		(1 "F.Mask" user "Board Geometry/Soldermask Top")
		(3 "B.Mask" user "Board Geometry/Soldermask Bottom")
		(17 "Dwgs.User" user "User.Drawings")
		(19 "Cmts.User" user "User.Comments")
		(21 "Eco1.User" user "User.Eco1")
		(23 "Eco2.User" user "User.Eco2")
		(25 "Edge.Cuts" user "Board Geometry/Outline")
		(27 "Margin" user)
		(31 "F.CrtYd" user "Package Geometry/Place Bound Top")
		(29 "B.CrtYd" user "Package Geometry/Place Bound Bottom")
		(35 "F.Fab" user "Ref Des/Assembly Top")
		(33 "B.Fab" user "Ref Des/Assembly Bottom")
	)
	(footprint ""
		(layer "F.Cu")
		(at 104.99979 -76.550012 180)
		(property "Reference" "U2D1"
			(at 25.19299 30.484318 0)
			(unlocked yes)
			(layer "F.SilkS")
			(effects
				(font
					(size 0.7874 0.5842)
					(thickness 0.1524)
				)
			)
		)
		(property "Value" ""
			(at 0 0 180)
			(layer "F.Fab")
			(effects
				(font
					(size 1.27 1.27)
				)
			)
		)
		(duplicate_pad_numbers_are_jumpers no)
		(pad "U12" smd circle
			(at -27.806904 -17.178528)
			(size 0.4318 0.4318)
			(layers "F.Cu" "F.Mask" "F.Paste")
			(net "UPI_CPU0_CPU1_P1P1_DN<6>")
		)
		(pad "U14" smd circle
			(at -26.090118 -17.178528)
			(size 0.4318 0.4318)
			(layers "F.Cu" "F.Mask" "F.Paste")
			(net "PVCCIO_CPU1")
		)
		(pad "U16" smd circle
			(at -24.373078 -17.178528)
			(size 0.4318 0.4318)
			(layers "F.Cu" "F.Mask" "F.Paste")
			(net "UPI_CPU0_CPU1_P1P1_DP<12>")
		)
		(pad "U18" smd circle
			(at -22.656038 -17.178528)
			(size 0.4318 0.4318)
			(layers "F.Cu" "F.Mask" "F.Paste")
			(net "UPI_CPU0_CPU1_P1P1_DN<15>")
		)
		(pad "U20" smd circle
			(at -20.938998 -17.178528)
			(size 0.4318 0.4318)
			(layers "F.Cu" "F.Mask" "F.Paste")
			(net "GND")
		)
		(pad "U22" smd circle
			(at -19.221958 -17.178528)
			(size 0.4318 0.4318)
			(layers "F.Cu" "F.Mask" "F.Paste")
			(net "GND")
		)
		(pad "U24" smd circle
			(at -17.504918 -17.178528)
			(size 0.4318 0.4318)
			(layers "F.Cu" "F.Mask" "F.Paste")
			(net "GND")
		)
		(pad "U26" smd circle
			(at -15.787878 -17.178528)
			(size 0.4318 0.4318)
			(layers "F.Cu" "F.Mask" "F.Paste")
			(net "M_H_DQ<62>")
		)
		(pad "U28" smd circle
			(at -14.071092 -17.178528)
			(size 0.4318 0.4318)
			(layers "F.Cu" "F.Mask" "F.Paste")
			(net "M_H_DQ<56>")
		)
		(pad "U30" smd circle
			(at -12.354052 -17.178528)
			(size 0.4318 0.4318)
			(layers "F.Cu" "F.Mask" "F.Paste")
			(net "GND")
		)
		(pad "U32" smd circle
			(at -10.637012 -17.178528)
			(size 0.4318 0.4318)
			(layers "F.Cu" "F.Mask" "F.Paste")
			(net "M_J_DQ<46>")
		)
		(pad "U34" smd circle
			(at -8.919972 -17.178528)
			(size 0.4318 0.4318)
			(layers "F.Cu" "F.Mask" "F.Paste")
			(net "M_J_DQ<40>")
		)
		(pad "U36" smd circle
			(at -7.202932 -17.178528)
			(size 0.4318 0.4318)
			(layers "F.Cu" "F.Mask" "F.Paste")
			(net "GND")
		)
		(pad "U38" smd circle
			(at -5.485892 -17.178528)
			(size 0.4318 0.4318)
			(layers "F.Cu" "F.Mask" "F.Paste")
			(net "M_J_DQ<38>")
		)
		(pad "U40" smd circle
			(at -3.769106 -17.178528)
			(size 0.4318 0.4318)
			(layers "F.Cu" "F.Mask" "F.Paste")
			(net "M_J_DQ<32>")
		)
		(pad "U42" smd circle
			(at -2.052066 -17.178528)
			(size 0.4318 0.4318)
			(layers "F.Cu" "F.Mask" "F.Paste")
			(net "GND")
		)
		(pad "U46" smd circle
			(at 2.910586 -18.978372)
			(size 0.4318 0.4318)
			(layers "F.Cu" "F.Mask" "F.Paste")
			(net "PVDDQ_GHJ")
		)
		(pad "U48" smd circle
			(at 4.627626 -18.978372)
			(size 0.4318 0.4318)
			(layers "F.Cu" "F.Mask" "F.Paste")
			(net "PVDDQ_GHJ")
		)
		(pad "U50" smd circle
			(at 6.344412 -18.978372)
			(size 0.4318 0.4318)
			(layers "F.Cu" "F.Mask" "F.Paste")
			(net "PVDDQ_GHJ")
		)
		(pad "U52" smd circle
			(at 8.061452 -18.978372)
			(size 0.4318 0.4318)
			(layers "F.Cu" "F.Mask" "F.Paste")
			(net "PVDDQ_GHJ")
		)
		(pad "U54" smd circle
			(at 9.778492 -18.978372)
			(size 0.4318 0.4318)
			(layers "F.Cu" "F.Mask" "F.Paste")
			(net "PVDDQ_GHJ")
		)
		(pad "U56" smd circle
			(at 11.495532 -18.978372)
			(size 0.4318 0.4318)
			(layers "F.Cu" "F.Mask" "F.Paste")
			(net "PVDDQ_GHJ")
		)
		(pad "U58" smd circle
			(at 13.212572 -18.978372)
			(size 0.4318 0.4318)
			(layers "F.Cu" "F.Mask" "F.Paste")
			(net "PVDDQ_GHJ")
		)
		(pad "U60" smd circle
			(at 14.929612 -18.978372)
			(size 0.4318 0.4318)
			(layers "F.Cu" "F.Mask" "F.Paste")
			(net "PVDDQ_GHJ")
		)
		(pad "U62" smd circle
			(at 16.646398 -18.978372)
			(size 0.4318 0.4318)
			(layers "F.Cu" "F.Mask" "F.Paste")
			(net "PVDDQ_GHJ")
		)
		(pad "U64" smd circle
			(at 18.363438 -18.978372)
			(size 0.4318 0.4318)
			(layers "F.Cu" "F.Mask" "F.Paste")
			(net "M_GHJ_RST_N")
		)
		(pad "U66" smd circle
			(at 20.080478 -18.978372)
			(size 0.4318 0.4318)
			(layers "F.Cu" "F.Mask" "F.Paste")
			(net "TP_CPU1_RSVD_261")
		)
		(pad "U68" smd circle
			(at 21.797518 -18.978372)
			(size 0.4318 0.4318)
			(layers "F.Cu" "F.Mask" "F.Paste")
			(net "GND")
		)
		(pad "U70" smd circle
			(at 23.514558 -18.978372)
			(size 0.4318 0.4318)
			(layers "F.Cu" "F.Mask" "F.Paste")
			(net "GND")
		)
		(pad "U72" smd circle
			(at 25.231598 -18.978372)
			(size 0.4318 0.4318)
			(layers "F.Cu" "F.Mask" "F.Paste")
			(net "M_J_DQS_DN<11>")
		)
		(pad "U74" smd circle
			(at 26.948384 -18.978372)
			(size 0.4318 0.4318)
			(layers "F.Cu" "F.Mask" "F.Paste")
			(net "GND")
		)
		(pad "U76" smd circle
			(at 28.665424 -18.978372)
			(size 0.4318 0.4318)
			(layers "F.Cu" "F.Mask" "F.Paste")
			(net "GND")
		)
		(pad "U78" smd circle
			(at 30.382464 -18.978372)
			(size 0.4318 0.4318)
			(layers "F.Cu" "F.Mask" "F.Paste")
			(net "GND")
		)
		(pad "U80" smd circle
			(at 32.099504 -18.978372)
			(size 0.4318 0.4318)
			(layers "F.Cu" "F.Mask" "F.Paste")
			(net "GND")
		)
		(pad "U82" smd circle
			(at 33.816544 -18.978372)
			(size 0.4318 0.4318)
			(layers "F.Cu" "F.Mask" "F.Paste")
			(net "M_G_DQS_DN<11>")
		)
		(pad "U84" smd circle
			(at 35.533584 -18.978372)
			(size 0.4318 0.4318)
			(layers "F.Cu" "F.Mask" "F.Paste")
			(net "M_G_DQS_DN<10>")
		)
		(pad "U86" smd custom
			(at 37.250624 -18.978372 270)
			(size 0.10795 0.10795)
			(layers "F.Cu" "F.Mask" "F.Paste")
			(net "GND")
			(options
				(clearance outline)
				(anchor circle)
			)
			(primitives
				(gr_poly
					(pts
						(arc
							(start 0.2159 -0.0381)
							(mid 0 -0.254)
							(end -0.2159 -0.0381)
						)
						(arc
							(start -0.2159 0.0381)
							(mid 0 0.254)
							(end 0.2159 0.0381)
						)
					)
					(width 0)
					(fill yes)
				)
			)
		)
		(pad "V1" smd custom
			(at -37.250624 -16.683228 90)
			(size 0.10795 0.10795)
			(layers "F.Cu" "F.Mask" "F.Paste")
			(net "GND")
			(options
				(clearance outline)
				(anchor circle)
			)
			(primitives
				(gr_poly
					(pts
						(arc
							(start 0.2159 -0.0381)
							(mid 0 -0.254)
							(end -0.2159 -0.0381)
						)
						(arc
							(start -0.2159 0.0381)
							(mid 0 0.254)
							(end 0.2159 0.0381)
						)
					)
					(width 0)
					(fill yes)
				)
			)
		)
		(pad "V3" smd circle
			(at -35.533584 -16.683228)
			(size 0.4318 0.4318)
			(layers "F.Cu" "F.Mask" "F.Paste")
			(net "UPI_CPU1_CPU0_P0P0_DN<2>")
		)
		(pad "V5" smd circle
			(at -33.816544 -16.683228)
			(size 0.4318 0.4318)
			(layers "F.Cu" "F.Mask" "F.Paste")
			(net "GND")
		)
		(pad "V7" smd circle
			(at -32.099504 -16.683228)
			(size 0.4318 0.4318)
			(layers "F.Cu" "F.Mask" "F.Paste")
			(net "UPI_CPU0_CPU1_P1P1_DN<2>")
		)
		(pad "V9" smd circle
			(at -30.382464 -16.683228)
			(size 0.4318 0.4318)
			(layers "F.Cu" "F.Mask" "F.Paste")
			(net "GND")
		)
		(pad "V11" smd circle
			(at -28.665424 -16.683228)
			(size 0.4318 0.4318)
			(layers "F.Cu" "F.Mask" "F.Paste")
			(net "GND")
		)
		(pad "V13" smd circle
			(at -26.948384 -16.683228)
			(size 0.4318 0.4318)
			(layers "F.Cu" "F.Mask" "F.Paste")
			(net "GND")
		)
		(pad "V15" smd circle
			(at -25.231598 -16.683228)
			(size 0.4318 0.4318)
			(layers "F.Cu" "F.Mask" "F.Paste")
			(net "GND")
		)
		(pad "V17" smd circle
			(at -23.514558 -16.683228)
			(size 0.4318 0.4318)
			(layers "F.Cu" "F.Mask" "F.Paste")
			(net "UPI_CPU0_CPU1_P1P1_DN<13>")
		)
		(pad "V19" smd circle
			(at -21.797518 -16.683228)
			(size 0.4318 0.4318)
			(layers "F.Cu" "F.Mask" "F.Paste")
			(net "UPI_CPU0_CPU1_P1P1_DN<17>")
		)
		(pad "V21" smd circle
			(at -20.080478 -16.683228)
			(size 0.4318 0.4318)
			(layers "F.Cu" "F.Mask" "F.Paste")
			(net "GND")
		)
		(pad "V23" smd circle
			(at -18.363438 -16.683228)
			(size 0.4318 0.4318)
			(layers "F.Cu" "F.Mask" "F.Paste")
			(net "GND")
		)
		(pad "V25" smd circle
			(at -16.646398 -16.683228)
			(size 0.4318 0.4318)
			(layers "F.Cu" "F.Mask" "F.Paste")
			(net "M_H_DQ<58>")
		)
		(pad "V27" smd circle
			(at -14.929612 -16.683228)
			(size 0.4318 0.4318)
			(layers "F.Cu" "F.Mask" "F.Paste")
			(net "M_H_DQS_DP<16>")
		)
		(pad "V29" smd circle
			(at -13.212572 -16.683228)
			(size 0.4318 0.4318)
			(layers "F.Cu" "F.Mask" "F.Paste")
			(net "M_H_DQ<60>")
		)
		(pad "V31" smd circle
			(at -11.495532 -16.683228)
			(size 0.4318 0.4318)
			(layers "F.Cu" "F.Mask" "F.Paste")
			(net "M_J_DQ<42>")
		)
		(pad "V33" smd circle
			(at -9.778492 -16.683228)
			(size 0.4318 0.4318)
			(layers "F.Cu" "F.Mask" "F.Paste")
			(net "M_J_DQS_DP<14>")
		)
		(pad "V35" smd circle
			(at -8.061452 -16.683228)
			(size 0.4318 0.4318)
			(layers "F.Cu" "F.Mask" "F.Paste")
			(net "M_J_DQ<44>")
		)
		(pad "V37" smd circle
			(at -6.344412 -16.683228)
			(size 0.4318 0.4318)
			(layers "F.Cu" "F.Mask" "F.Paste")
			(net "M_J_DQ<34>")
		)
		(pad "V39" smd circle
			(at -4.627626 -16.683228)
			(size 0.4318 0.4318)
			(layers "F.Cu" "F.Mask" "F.Paste")
			(net "M_J_DQS_DP<13>")
		)
		(pad "V41" smd circle
			(at -2.910586 -16.683228)
			(size 0.4318 0.4318)
			(layers "F.Cu" "F.Mask" "F.Paste")
			(net "M_J_DQ<36>")
		)
		(pad "V43" smd circle
			(at -1.193546 -16.683228)
			(size 0.4318 0.4318)
			(layers "F.Cu" "F.Mask" "F.Paste")
			(net "GND")
		)
		(pad "V45" smd circle
			(at 2.052066 -18.483072)
			(size 0.508 0.508)
			(layers "F.Cu" "F.Mask" "F.Paste")
			(net "M_J_CS_N<7>")
		)
		(pad "V47" smd circle
			(at 3.769106 -18.483072)
			(size 0.4318 0.4318)
			(layers "F.Cu" "F.Mask" "F.Paste")
			(net "M_H_CS_N<3>")
		)
		(pad "V49" smd circle
			(at 5.485892 -18.483072)
			(size 0.4318 0.4318)
			(layers "F.Cu" "F.Mask" "F.Paste")
			(net "M_J_ODT<2>")
		)
		(pad "V51" smd circle
			(at 7.202932 -18.483072)
			(size 0.4318 0.4318)
			(layers "F.Cu" "F.Mask" "F.Paste")
			(net "M_J_CS_N<0>")
		)
		(pad "V53" smd circle
			(at 8.919972 -18.483072)
			(size 0.4318 0.4318)
			(layers "F.Cu" "F.Mask" "F.Paste")
			(net "M_J_PAR")
		)
		(pad "V55" smd circle
			(at 10.637012 -18.483072)
			(size 0.4318 0.4318)
			(layers "F.Cu" "F.Mask" "F.Paste")
			(net "M_J_CLK_DP<1>")
		)
		(pad "V57" smd circle
			(at 12.354052 -18.483072)
			(size 0.4318 0.4318)
			(layers "F.Cu" "F.Mask" "F.Paste")
			(net "M_J_CLK_DP<3>")
		)
		(pad "V59" smd circle
			(at 14.071092 -18.483072)
			(size 0.4318 0.4318)
			(layers "F.Cu" "F.Mask" "F.Paste")
			(net "M_J_MA<5>")
		)
		(pad "V61" smd circle
			(at 15.787878 -18.483072)
			(size 0.4318 0.4318)
			(layers "F.Cu" "F.Mask" "F.Paste")
			(net "M_H_MA<7>")
		)
		(pad "V63" smd circle
			(at 17.504918 -18.483072)
			(size 0.4318 0.4318)
			(layers "F.Cu" "F.Mask" "F.Paste")
			(net "M_J_CKE<2>")
		)
		(pad "V65" smd circle
			(at 19.221958 -18.483072)
			(size 0.4318 0.4318)
			(layers "F.Cu" "F.Mask" "F.Paste")
			(net "TP_CPU1_RSVD_260")
		)
		(pad "V67" smd circle
			(at 20.938998 -18.483072)
			(size 0.4318 0.4318)
			(layers "F.Cu" "F.Mask" "F.Paste")
			(net "TP_CPU1_RSVD_259")
		)
		(pad "V69" smd circle
			(at 22.656038 -18.483072)
			(size 0.4318 0.4318)
			(layers "F.Cu" "F.Mask" "F.Paste")
			(net "M_J_DQ<23>")
		)
		(pad "V71" smd circle
			(at 24.373078 -18.483072)
			(size 0.4318 0.4318)
			(layers "F.Cu" "F.Mask" "F.Paste")
			(net "M_J_DQS_DP<11>")
		)
		(pad "V73" smd circle
			(at 26.090118 -18.483072)
			(size 0.4318 0.4318)
			(layers "F.Cu" "F.Mask" "F.Paste")
			(net "GND")
		)
		(pad "V75" smd circle
			(at 27.806904 -18.483072)
			(size 0.4318 0.4318)
			(layers "F.Cu" "F.Mask" "F.Paste")
			(net "GND")
		)
		(pad "V77" smd circle
			(at 29.523944 -18.483072)
			(size 0.4318 0.4318)
			(layers "F.Cu" "F.Mask" "F.Paste")
			(net "GND")
		)
		(pad "V79" smd circle
			(at 31.240984 -18.483072)
			(size 0.4318 0.4318)
			(layers "F.Cu" "F.Mask" "F.Paste")
			(net "M_G_DQ<21>")
		)
		(pad "V81" smd circle
			(at 32.958024 -18.483072)
			(size 0.4318 0.4318)
			(layers "F.Cu" "F.Mask" "F.Paste")
			(net "M_G_DQ<16>")
		)
		(pad "V83" smd circle
			(at 34.675064 -18.483072)
			(size 0.4318 0.4318)
			(layers "F.Cu" "F.Mask" "F.Paste")
			(net "GND")
		)
		(pad "V85" smd circle
			(at 36.392104 -18.483072)
			(size 0.4318 0.4318)
			(layers "F.Cu" "F.Mask" "F.Paste")
			(net "M_G_DQS_DP<10>")
		)
		(pad "W2" smd circle
			(at -36.392104 -16.187674)
			(size 0.4318 0.4318)
			(layers "F.Cu" "F.Mask" "F.Paste")
			(net "UPI_CPU1_CPU0_P0P0_DP<3>")
		)
		(pad "W4" smd circle
			(at -34.675064 -16.187674)
			(size 0.4318 0.4318)
			(layers "F.Cu" "F.Mask" "F.Paste")
			(net "PVCCIO_CPU1")
		)
		(pad "W6" smd circle
			(at -32.958024 -16.187674)
			(size 0.4318 0.4318)
			(layers "F.Cu" "F.Mask" "F.Paste")
			(net "PVCCIO_CPU1")
		)
		(pad "W8" smd circle
			(at -31.240984 -16.187674)
			(size 0.4318 0.4318)
			(layers "F.Cu" "F.Mask" "F.Paste")
			(net "GND")
		)
		(pad "W10" smd circle
			(at -29.523944 -16.187674)
			(size 0.4318 0.4318)
			(layers "F.Cu" "F.Mask" "F.Paste")
			(net "PVCCIO_CPU1")
		)
		(pad "W12" smd circle
			(at -27.806904 -16.187674)
			(size 0.4318 0.4318)
			(layers "F.Cu" "F.Mask" "F.Paste")
			(net "GND")
		)
		(pad "W14" smd circle
			(at -26.090118 -16.187674)
			(size 0.4318 0.4318)
			(layers "F.Cu" "F.Mask" "F.Paste")
			(net "XDP_CPU_TMS")
		)
		(pad "W16" smd circle
			(at -24.373078 -16.187674)
			(size 0.4318 0.4318)
			(layers "F.Cu" "F.Mask" "F.Paste")
			(net "UPI_CPU0_CPU1_P1P1_DN<12>")
		)
		(pad "W18" smd circle
			(at -22.656038 -16.187674)
			(size 0.4318 0.4318)
			(layers "F.Cu" "F.Mask" "F.Paste")
			(net "UPI_CPU0_CPU1_P1P1_DP<13>")
		)
		(pad "W20" smd circle
			(at -20.938998 -16.187674)
			(size 0.4318 0.4318)
			(layers "F.Cu" "F.Mask" "F.Paste")
			(net "UPI_CPU0_CPU1_P1P1_DN<18>")
		)
		(pad "W22" smd circle
			(at -19.221958 -16.187674)
			(size 0.4318 0.4318)
			(layers "F.Cu" "F.Mask" "F.Paste")
			(net "GND")
		)
		(pad "W24" smd circle
			(at -17.504918 -16.187674)
			(size 0.4318 0.4318)
			(layers "F.Cu" "F.Mask" "F.Paste")
			(net "GND")
		)
		(pad "W26" smd circle
			(at -15.787878 -16.187674)
			(size 0.4318 0.4318)
			(layers "F.Cu" "F.Mask" "F.Paste")
			(net "GND")
		)
		(pad "W28" smd circle
			(at -14.071092 -16.187674)
			(size 0.4318 0.4318)
			(layers "F.Cu" "F.Mask" "F.Paste")
			(net "GND")
		)
		(pad "W30" smd circle
			(at -12.354052 -16.187674)
			(size 0.4318 0.4318)
			(layers "F.Cu" "F.Mask" "F.Paste")
			(net "GND")
		)
		(pad "W32" smd circle
			(at -10.637012 -16.187674)
			(size 0.4318 0.4318)
			(layers "F.Cu" "F.Mask" "F.Paste")
			(net "GND")
		)
		(pad "W34" smd circle
			(at -8.919972 -16.187674)
			(size 0.4318 0.4318)
			(layers "F.Cu" "F.Mask" "F.Paste")
			(net "GND")
		)
		(pad "W36" smd circle
			(at -7.202932 -16.187674)
			(size 0.4318 0.4318)
			(layers "F.Cu" "F.Mask" "F.Paste")
			(net "GND")
		)
		(pad "W38" smd circle
			(at -5.485892 -16.187674)
			(size 0.4318 0.4318)
			(layers "F.Cu" "F.Mask" "F.Paste")
			(net "GND")
		)
		(pad "W40" smd circle
			(at -3.769106 -16.187674)
			(size 0.4318 0.4318)
			(layers "F.Cu" "F.Mask" "F.Paste")
			(net "GND")
		)
		(pad "W42" smd circle
			(at -2.052066 -16.187674)
			(size 0.4318 0.4318)
			(layers "F.Cu" "F.Mask" "F.Paste")
			(net "GND")
		)
		(pad "W46" smd circle
			(at 2.910586 -17.988026)
			(size 0.4318 0.4318)
			(layers "F.Cu" "F.Mask" "F.Paste")
			(net "M_J_CS_N<2>")
		)
		(pad "W48" smd circle
			(at 4.627626 -17.988026)
			(size 0.4318 0.4318)
			(layers "F.Cu" "F.Mask" "F.Paste")
			(net "M_J_CS_N<5>")
		)
		(pad "W50" smd circle
			(at 6.344412 -17.988026)
			(size 0.4318 0.4318)
			(layers "F.Cu" "F.Mask" "F.Paste")
			(net "M_J_MA<14>")
		)
		(pad "W52" smd circle
			(at 8.061452 -17.988026)
			(size 0.4318 0.4318)
			(layers "F.Cu" "F.Mask" "F.Paste")
			(net "M_J_BA<0>")
		)
		(pad "W54" smd circle
			(at 9.778492 -17.988026)
			(size 0.4318 0.4318)
			(layers "F.Cu" "F.Mask" "F.Paste")
			(net "M_J_CLK_DN<1>")
		)
		(pad "W56" smd circle
			(at 11.495532 -17.988026)
			(size 0.4318 0.4318)
			(layers "F.Cu" "F.Mask" "F.Paste")
			(net "M_J_CLK_DN<3>")
		)
		(pad "W58" smd circle
			(at 13.212572 -17.988026)
			(size 0.4318 0.4318)
			(layers "F.Cu" "F.Mask" "F.Paste")
			(net "M_J_MA<3>")
		)
		(pad "W60" smd circle
			(at 14.929612 -17.988026)
			(size 0.4318 0.4318)
			(layers "F.Cu" "F.Mask" "F.Paste")
			(net "M_H_MA<8>")
		)
		(pad "W62" smd circle
			(at 16.646398 -17.988026)
			(size 0.4318 0.4318)
			(layers "F.Cu" "F.Mask" "F.Paste")
			(net "M_H_ALERT_N")
		)
		(pad "W64" smd circle
			(at 18.363438 -17.988026)
			(size 0.4318 0.4318)
			(layers "F.Cu" "F.Mask" "F.Paste")
			(net "PVDDQ_GHJ")
		)
		(pad "W66" smd circle
			(at 20.080478 -17.988026)
			(size 0.4318 0.4318)
			(layers "F.Cu" "F.Mask" "F.Paste")
			(net "TP_CPU1_RSVD_258")
		)
		(pad "W68" smd circle
			(at 21.797518 -17.988026)
			(size 0.4318 0.4318)
			(layers "F.Cu" "F.Mask" "F.Paste")
			(net "GND")
		)
	)
)
